(kicad_pcb
	(version 20260206)
	(generator "pcbnew")
	(generator_version "10.0")
	(general
		(thickness 1.6)
		(legacy_teardrops no)
	)
	(paper "A4")
	(title_block
		(title "03242023_DA0F0TMBIJ0_F0T_Motherboard_J_brd_V01_OCP.brd")
		(comment 1 "Grand Teton / footprints 4453-4459 of 6105")
	)
	(layers
		(0 "F.Cu" signal "TOP")
		(4 "In1.Cu" signal "GND")
		(6 "In2.Cu" signal "IN1")
		(8 "In3.Cu" signal "GND1")
		(10 "In4.Cu" signal "IN2")
		(12 "In5.Cu" signal "GND2")
		(14 "In6.Cu" signal "IN3")
		(16 "In7.Cu" signal "GND3")
		(18 "In8.Cu" signal "VCC")
		(20 "In9.Cu" signal "VCC1")
		(22 "In10.Cu" signal "GND4")
		(24 "In11.Cu" signal "IN4")
		(26 "In12.Cu" signal "GND5")
		(28 "In13.Cu" signal "IN5")
		(30 "In14.Cu" signal "GND6")
		(32 "In15.Cu" signal "IN6")
		(34 "In16.Cu" signal "GND7")
		(2 "B.Cu" signal "BOTTOM")
		(9 "F.Adhes" user "F.Adhesive")
		(11 "B.Adhes" user "B.Adhesive")
		(13 "F.Paste" user "Package Geometry/Pastemask Top")
		(15 "B.Paste" user "Package Geometry/Pastemask Bottom")
		(5 "F.SilkS" user "Ref Des/Silkscreen Top")
		(7 "B.SilkS" user "Ref Des/Silkscreen Bottom")
		(1 "F.Mask" user "Board Geometry/Soldermask Top")
		(3 "B.Mask" user "Board Geometry/Soldermask Bottom")
		(17 "Dwgs.User" user "User.Drawings")
		(19 "Cmts.User" user "User.Comments")
		(21 "Eco1.User" user "User.Eco1")
		(23 "Eco2.User" user "User.Eco2")
		(25 "Edge.Cuts" user "Board Geometry/Outline")
		(27 "Margin" user)
		(31 "F.CrtYd" user "Package Geometry/Place Bound Top")
		(29 "B.CrtYd" user "Package Geometry/Place Bound Bottom")
		(35 "F.Fab" user "Ref Des/Assembly Top")
		(33 "B.Fab" user "Ref Des/Assembly Bottom")
	)
	(footprint ""
		(layer "B.Cu")
		(at 205.446122 -108.490766 90)
		(property "Reference" "R4533"
			(at 0 0 90)
			(layer "B.SilkS")
			(hide yes)
			(effects
				(font
					(size 1.27 1.27)
				)
				(justify mirror)
			)
		)
		(property "Value" ""
			(at 0 0 90)
			(layer "B.Fab")
			(effects
				(font
					(size 1.27 1.27)
				)
				(justify mirror)
			)
		)
		(duplicate_pad_numbers_are_jumpers no)
		(fp_line
			(start 0.7874 -0.4064)
			(end -0.7874 -0.4064)
			(stroke
				(width 0.1524)
				(type default)
			)
			(layer "B.SilkS")
		)
		(fp_line
			(start -0.7874 -0.4064)
			(end -0.7874 0.4064)
			(stroke
				(width 0.1524)
				(type default)
			)
			(layer "B.SilkS")
		)
		(fp_line
			(start 0.7874 0.4064)
			(end 0.7874 -0.4064)
			(stroke
				(width 0.1524)
				(type default)
			)
			(layer "B.SilkS")
		)
		(fp_line
			(start -0.7874 0.4064)
			(end 0.7874 0.4064)
			(stroke
				(width 0.1524)
				(type default)
			)
			(layer "B.SilkS")
		)
		(fp_line
			(start 0.67945 -0.305054)
			(end 0.12065 -0.305054)
			(stroke
				(width 0.1)
				(type default)
			)
			(layer "B.Fab")
		)
		(fp_line
			(start 0.12065 -0.305054)
			(end 0.12065 -0.2794)
			(stroke
				(width 0.1)
				(type default)
			)
			(layer "B.Fab")
		)
		(fp_line
			(start -0.12065 -0.3048)
			(end -0.67945 -0.3048)
			(stroke
				(width 0.1)
				(type default)
			)
			(layer "B.Fab")
		)
		(fp_line
			(start -0.67945 -0.3048)
			(end -0.67945 0.3048)
			(stroke
				(width 0.1)
				(type default)
			)
			(layer "B.Fab")
		)
		(fp_line
			(start 0.12065 -0.2794)
			(end -0.12065 -0.2794)
			(stroke
				(width 0.1)
				(type default)
			)
			(layer "B.Fab")
		)
		(fp_line
			(start -0.12065 -0.2794)
			(end -0.12065 -0.3048)
			(stroke
				(width 0.1)
				(type default)
			)
			(layer "B.Fab")
		)
		(fp_line
			(start 0.12065 0.2794)
			(end 0.12065 0.3048)
			(stroke
				(width 0.1)
				(type default)
			)
			(layer "B.Fab")
		)
		(fp_line
			(start -0.120396 0.2794)
			(end 0.12065 0.2794)
			(stroke
				(width 0.1)
				(type default)
			)
			(layer "B.Fab")
		)
		(fp_line
			(start 0.67945 0.3048)
			(end 0.67945 -0.305054)
			(stroke
				(width 0.1)
				(type default)
			)
			(layer "B.Fab")
		)
		(fp_line
			(start 0.12065 0.3048)
			(end 0.67945 0.3048)
			(stroke
				(width 0.1)
				(type default)
			)
			(layer "B.Fab")
		)
		(fp_line
			(start -0.120396 0.3048)
			(end -0.120396 0.2794)
			(stroke
				(width 0.1)
				(type default)
			)
			(layer "B.Fab")
		)
		(fp_line
			(start -0.67945 0.3048)
			(end -0.120396 0.3048)
			(stroke
				(width 0.1)
				(type default)
			)
			(layer "B.Fab")
		)
		(pad "1" smd circle
			(at 0.40005 0 270)
			(size 0 0)
			(layers "B.Cu" "B.Mask" "B.Paste")
			(net "PWRGD_DRAMPWRGD_CPU1_GH_R_LVC1")
		)
		(pad "2" smd circle
			(at -0.40005 0 270)
			(size 0 0)
			(layers "B.Cu" "B.Mask" "B.Paste")
			(net "GND")
		)
	)
	(footprint ""
		(layer "B.Cu")
		(at 239.2934 -422.9862 90)
		(property "Reference" "C2293"
			(at 0 0 90)
			(layer "B.SilkS")
			(hide yes)
			(effects
				(font
					(size 1.27 1.27)
				)
				(justify mirror)
			)
		)
		(property "Value" ""
			(at 0 0 90)
			(layer "B.Fab")
			(effects
				(font
					(size 1.27 1.27)
				)
				(justify mirror)
			)
		)
		(duplicate_pad_numbers_are_jumpers no)
		(fp_line
			(start 0.7874 -0.4064)
			(end -0.7874 -0.4064)
			(stroke
				(width 0.1524)
				(type default)
			)
			(layer "B.SilkS")
		)
		(fp_line
			(start -0.7874 -0.4064)
			(end -0.7874 0.4064)
			(stroke
				(width 0.1524)
				(type default)
			)
			(layer "B.SilkS")
		)
		(fp_line
			(start 0.7874 0.4064)
			(end 0.7874 -0.4064)
			(stroke
				(width 0.1524)
				(type default)
			)
			(layer "B.SilkS")
		)
		(fp_line
			(start -0.7874 0.4064)
			(end 0.7874 0.4064)
			(stroke
				(width 0.1524)
				(type default)
			)
			(layer "B.SilkS")
		)
		(fp_line
			(start 0.67945 -0.305054)
			(end 0.12065 -0.305054)
			(stroke
				(width 0.1)
				(type default)
			)
			(layer "B.Fab")
		)
		(fp_line
			(start 0.12065 -0.305054)
			(end 0.12065 -0.2794)
			(stroke
				(width 0.1)
				(type default)
			)
			(layer "B.Fab")
		)
		(fp_line
			(start -0.12065 -0.3048)
			(end -0.67945 -0.3048)
			(stroke
				(width 0.1)
				(type default)
			)
			(layer "B.Fab")
		)
		(fp_line
			(start -0.67945 -0.3048)
			(end -0.67945 0.3048)
			(stroke
				(width 0.1)
				(type default)
			)
			(layer "B.Fab")
		)
		(fp_line
			(start 0.12065 -0.2794)
			(end -0.12065 -0.2794)
			(stroke
				(width 0.1)
				(type default)
			)
			(layer "B.Fab")
		)
		(fp_line
			(start -0.12065 -0.2794)
			(end -0.12065 -0.3048)
			(stroke
				(width 0.1)
				(type default)
			)
			(layer "B.Fab")
		)
		(fp_line
			(start 0.12065 0.2794)
			(end 0.12065 0.3048)
			(stroke
				(width 0.1)
				(type default)
			)
			(layer "B.Fab")
		)
		(fp_line
			(start -0.120396 0.2794)
			(end 0.12065 0.2794)
			(stroke
				(width 0.1)
				(type default)
			)
			(layer "B.Fab")
		)
		(fp_line
			(start 0.67945 0.3048)
			(end 0.67945 -0.305054)
			(stroke
				(width 0.1)
				(type default)
			)
			(layer "B.Fab")
		)
		(fp_line
			(start 0.12065 0.3048)
			(end 0.67945 0.3048)
			(stroke
				(width 0.1)
				(type default)
			)
			(layer "B.Fab")
		)
		(fp_line
			(start -0.120396 0.3048)
			(end -0.120396 0.2794)
			(stroke
				(width 0.1)
				(type default)
			)
			(layer "B.Fab")
		)
		(fp_line
			(start -0.67945 0.3048)
			(end -0.120396 0.3048)
			(stroke
				(width 0.1)
				(type default)
			)
			(layer "B.Fab")
		)
		(pad "1" smd circle
			(at 0.40005 0 270)
			(size 0 0)
			(layers "B.Cu" "B.Mask" "B.Paste")
			(net "RST_SMB_SWITCH_R_N")
		)
		(pad "2" smd circle
			(at -0.40005 0 270)
			(size 0 0)
			(layers "B.Cu" "B.Mask" "B.Paste")
			(net "GND")
		)
	)
	(footprint ""
		(layer "B.Cu")
		(at 345.5543 -64.088264 90)
		(property "Reference" "C160"
			(at 0 0 90)
			(layer "B.SilkS")
			(hide yes)
			(effects
				(font
					(size 1.27 1.27)
				)
				(justify mirror)
			)
		)
		(property "Value" ""
			(at 0 0 90)
			(layer "B.Fab")
			(effects
				(font
					(size 1.27 1.27)
				)
				(justify mirror)
			)
		)
		(duplicate_pad_numbers_are_jumpers no)
		(fp_line
			(start 0.299974 -0.150114)
			(end -0.299974 -0.150114)
			(stroke
				(width 0.1)
				(type default)
			)
			(layer "B.Fab")
		)
		(fp_line
			(start -0.299974 -0.150114)
			(end -0.299974 0.150114)
			(stroke
				(width 0.1)
				(type default)
			)
			(layer "B.Fab")
		)
		(fp_line
			(start 0.299974 0.150114)
			(end 0.299974 -0.150114)
			(stroke
				(width 0.1)
				(type default)
			)
			(layer "B.Fab")
		)
		(fp_line
			(start -0.299974 0.150114)
			(end 0.299974 0.150114)
			(stroke
				(width 0.1)
				(type default)
			)
			(layer "B.Fab")
		)
		(pad "1" smd rect
			(at 0.2667 0 270)
			(size 0.3048 0.381)
			(layers "B.Cu" "B.Mask" "B.Paste")
			(net "DMI_CPU0_PCH_RX_C_DP<5>")
		)
		(pad "2" smd rect
			(at -0.2667 0 270)
			(size 0.3048 0.381)
			(layers "B.Cu" "B.Mask" "B.Paste")
			(net "DMI_CPU0_PCH_RX_DP<5>")
		)
	)
	(footprint ""
		(layer "B.Cu")
		(at 156.580078 -101.637846)
		(property "Reference" "R1329"
			(at 0 0 0)
			(layer "B.SilkS")
			(hide yes)
			(effects
				(font
					(size 1.27 1.27)
				)
				(justify mirror)
			)
		)
		(property "Value" ""
			(at 0 0 0)
			(layer "B.Fab")
			(effects
				(font
					(size 1.27 1.27)
				)
				(justify mirror)
			)
		)
		(duplicate_pad_numbers_are_jumpers no)
		(fp_line
			(start -0.7874 -0.4064)
			(end -0.7874 0.4064)
			(stroke
				(width 0.1524)
				(type default)
			)
			(layer "B.SilkS")
		)
		(fp_line
			(start -0.7874 0.4064)
			(end 0.7874 0.4064)
			(stroke
				(width 0.1524)
				(type default)
			)
			(layer "B.SilkS")
		)
		(fp_line
			(start 0.7874 -0.4064)
			(end -0.7874 -0.4064)
			(stroke
				(width 0.1524)
				(type default)
			)
			(layer "B.SilkS")
		)
		(fp_line
			(start 0.7874 0.4064)
			(end 0.7874 -0.4064)
			(stroke
				(width 0.1524)
				(type default)
			)
			(layer "B.SilkS")
		)
		(fp_line
			(start -0.67945 -0.3048)
			(end -0.67945 0.3048)
			(stroke
				(width 0.1)
				(type default)
			)
			(layer "B.Fab")
		)
		(fp_line
			(start -0.67945 0.3048)
			(end -0.120396 0.3048)
			(stroke
				(width 0.1)
				(type default)
			)
			(layer "B.Fab")
		)
		(fp_line
			(start -0.12065 -0.3048)
			(end -0.67945 -0.3048)
			(stroke
				(width 0.1)
				(type default)
			)
			(layer "B.Fab")
		)
		(fp_line
			(start -0.12065 -0.2794)
			(end -0.12065 -0.3048)
			(stroke
				(width 0.1)
				(type default)
			)
			(layer "B.Fab")
		)
		(fp_line
			(start -0.120396 0.2794)
			(end 0.12065 0.2794)
			(stroke
				(width 0.1)
				(type default)
			)
			(layer "B.Fab")
		)
		(fp_line
			(start -0.120396 0.3048)
			(end -0.120396 0.2794)
			(stroke
				(width 0.1)
				(type default)
			)
			(layer "B.Fab")
		)
		(fp_line
			(start 0.12065 -0.305054)
			(end 0.12065 -0.2794)
			(stroke
				(width 0.1)
				(type default)
			)
			(layer "B.Fab")
		)
		(fp_line
			(start 0.12065 -0.2794)
			(end -0.12065 -0.2794)
			(stroke
				(width 0.1)
				(type default)
			)
			(layer "B.Fab")
		)
		(fp_line
			(start 0.12065 0.2794)
			(end 0.12065 0.3048)
			(stroke
				(width 0.1)
				(type default)
			)
			(layer "B.Fab")
		)
		(fp_line
			(start 0.12065 0.3048)
			(end 0.67945 0.3048)
			(stroke
				(width 0.1)
				(type default)
			)
			(layer "B.Fab")
		)
		(fp_line
			(start 0.67945 -0.305054)
			(end 0.12065 -0.305054)
			(stroke
				(width 0.1)
				(type default)
			)
			(layer "B.Fab")
		)
		(fp_line
			(start 0.67945 0.3048)
			(end 0.67945 -0.305054)
			(stroke
				(width 0.1)
				(type default)
			)
			(layer "B.Fab")
		)
		(pad "1" smd circle
			(at 0.40005 0 180)
			(size 0 0)
			(layers "B.Cu" "B.Mask" "B.Paste")
			(net "PWRGD_DRAMPWRGD_CPU1_AB_R_LVC1")
		)
		(pad "2" smd circle
			(at -0.40005 0 180)
			(size 0 0)
			(layers "B.Cu" "B.Mask" "B.Paste")
			(net "GND")
		)
	)
	(footprint ""
		(layer "B.Cu")
		(at 340.889844 -49.66462 180)
		(property "Reference" "C1263"
			(at 0 0 0)
			(layer "B.SilkS")
			(hide yes)
			(effects
				(font
					(size 1.27 1.27)
				)
				(justify mirror)
			)
		)
		(property "Value" ""
			(at 0 0 0)
			(layer "B.Fab")
			(effects
				(font
					(size 1.27 1.27)
				)
				(justify mirror)
			)
		)
		(duplicate_pad_numbers_are_jumpers no)
		(fp_line
			(start 0.7874 0.4064)
			(end 0.7874 -0.4064)
			(stroke
				(width 0.1524)
				(type default)
			)
			(layer "B.SilkS")
		)
		(fp_line
			(start 0.7874 -0.4064)
			(end -0.7874 -0.4064)
			(stroke
				(width 0.1524)
				(type default)
			)
			(layer "B.SilkS")
		)
		(fp_line
			(start -0.7874 0.4064)
			(end 0.7874 0.4064)
			(stroke
				(width 0.1524)
				(type default)
			)
			(layer "B.SilkS")
		)
		(fp_line
			(start -0.7874 -0.4064)
			(end -0.7874 0.4064)
			(stroke
				(width 0.1524)
				(type default)
			)
			(layer "B.SilkS")
		)
		(fp_line
			(start 0.67945 0.3048)
			(end 0.67945 -0.305054)
			(stroke
				(width 0.1)
				(type default)
			)
			(layer "B.Fab")
		)
		(fp_line
			(start 0.67945 -0.305054)
			(end 0.12065 -0.305054)
			(stroke
				(width 0.1)
				(type default)
			)
			(layer "B.Fab")
		)
		(fp_line
			(start 0.12065 0.3048)
			(end 0.67945 0.3048)
			(stroke
				(width 0.1)
				(type default)
			)
			(layer "B.Fab")
		)
		(fp_line
			(start 0.12065 0.2794)
			(end 0.12065 0.3048)
			(stroke
				(width 0.1)
				(type default)
			)
			(layer "B.Fab")
		)
		(fp_line
			(start 0.12065 -0.2794)
			(end -0.12065 -0.2794)
			(stroke
				(width 0.1)
				(type default)
			)
			(layer "B.Fab")
		)
		(fp_line
			(start 0.12065 -0.305054)
			(end 0.12065 -0.2794)
			(stroke
				(width 0.1)
				(type default)
			)
			(layer "B.Fab")
		)
		(fp_line
			(start -0.120396 0.3048)
			(end -0.120396 0.2794)
			(stroke
				(width 0.1)
				(type default)
			)
			(layer "B.Fab")
		)
		(fp_line
			(start -0.120396 0.2794)
			(end 0.12065 0.2794)
			(stroke
				(width 0.1)
				(type default)
			)
			(layer "B.Fab")
		)
		(fp_line
			(start -0.12065 -0.2794)
			(end -0.12065 -0.3048)
			(stroke
				(width 0.1)
				(type default)
			)
			(layer "B.Fab")
		)
		(fp_line
			(start -0.12065 -0.3048)
			(end -0.67945 -0.3048)
			(stroke
				(width 0.1)
				(type default)
			)
			(layer "B.Fab")
		)
		(fp_line
			(start -0.67945 0.3048)
			(end -0.120396 0.3048)
			(stroke
				(width 0.1)
				(type default)
			)
			(layer "B.Fab")
		)
		(fp_line
			(start -0.67945 -0.3048)
			(end -0.67945 0.3048)
			(stroke
				(width 0.1)
				(type default)
			)
			(layer "B.Fab")
		)
		(pad "1" smd circle
			(at 0.40005 0)
			(size 0 0)
			(layers "B.Cu" "B.Mask" "B.Paste")
			(net "P1V8_PCH_PLL_AUX")
		)
		(pad "2" smd circle
			(at -0.40005 0)
			(size 0 0)
			(layers "B.Cu" "B.Mask" "B.Paste")
			(net "GND")
		)
	)
	(footprint ""
		(layer "B.Cu")
		(at 276.147784 -193.669666 -90)
		(property "Reference" "R251"
			(at 0 0 90)
			(layer "B.SilkS")
			(hide yes)
			(effects
				(font
					(size 1.27 1.27)
				)
				(justify mirror)
			)
		)
		(property "Value" ""
			(at 0 0 90)
			(layer "B.Fab")
			(effects
				(font
					(size 1.27 1.27)
				)
				(justify mirror)
			)
		)
		(duplicate_pad_numbers_are_jumpers no)
		(fp_line
			(start -0.7874 0.4064)
			(end 0.7874 0.4064)
			(stroke
				(width 0.1524)
				(type default)
			)
			(layer "B.SilkS")
		)
		(fp_line
			(start 0.7874 0.4064)
			(end 0.7874 -0.4064)
			(stroke
				(width 0.1524)
				(type default)
			)
			(layer "B.SilkS")
		)
		(fp_line
			(start -0.7874 -0.4064)
			(end -0.7874 0.4064)
			(stroke
				(width 0.1524)
				(type default)
			)
			(layer "B.SilkS")
		)
		(fp_line
			(start 0.7874 -0.4064)
			(end -0.7874 -0.4064)
			(stroke
				(width 0.1524)
				(type default)
			)
			(layer "B.SilkS")
		)
		(fp_line
			(start -0.67945 0.3048)
			(end -0.120396 0.3048)
			(stroke
				(width 0.1)
				(type default)
			)
			(layer "B.Fab")
		)
		(fp_line
			(start -0.120396 0.3048)
			(end -0.120396 0.2794)
			(stroke
				(width 0.1)
				(type default)
			)
			(layer "B.Fab")
		)
		(fp_line
			(start 0.12065 0.3048)
			(end 0.67945 0.3048)
			(stroke
				(width 0.1)
				(type default)
			)
			(layer "B.Fab")
		)
		(fp_line
			(start 0.67945 0.3048)
			(end 0.67945 -0.305054)
			(stroke
				(width 0.1)
				(type default)
			)
			(layer "B.Fab")
		)
		(fp_line
			(start -0.120396 0.2794)
			(end 0.12065 0.2794)
			(stroke
				(width 0.1)
				(type default)
			)
			(layer "B.Fab")
		)
		(fp_line
			(start 0.12065 0.2794)
			(end 0.12065 0.3048)
			(stroke
				(width 0.1)
				(type default)
			)
			(layer "B.Fab")
		)
		(fp_line
			(start -0.12065 -0.2794)
			(end -0.12065 -0.3048)
			(stroke
				(width 0.1)
				(type default)
			)
			(layer "B.Fab")
		)
		(fp_line
			(start 0.12065 -0.2794)
			(end -0.12065 -0.2794)
			(stroke
				(width 0.1)
				(type default)
			)
			(layer "B.Fab")
		)
		(fp_line
			(start -0.67945 -0.3048)
			(end -0.67945 0.3048)
			(stroke
				(width 0.1)
				(type default)
			)
			(layer "B.Fab")
		)
		(fp_line
			(start -0.12065 -0.3048)
			(end -0.67945 -0.3048)
			(stroke
				(width 0.1)
				(type default)
			)
			(layer "B.Fab")
		)
		(fp_line
			(start 0.12065 -0.305054)
			(end 0.12065 -0.2794)
			(stroke
				(width 0.1)
				(type default)
			)
			(layer "B.Fab")
		)
		(fp_line
			(start 0.67945 -0.305054)
			(end 0.12065 -0.305054)
			(stroke
				(width 0.1)
				(type default)
			)
			(layer "B.Fab")
		)
		(pad "1" smd circle
			(at 0.40005 0 90)
			(size 0 0)
			(layers "B.Cu" "B.Mask" "B.Paste")
			(net "PVNN_TERM_CPU0")
		)
		(pad "2" smd circle
			(at -0.40005 0 90)
			(size 0 0)
			(layers "B.Cu" "B.Mask" "B.Paste")
			(net "FM_S3M_CPU0_LVC1_GPIO_4")
		)
	)
	(footprint ""
		(layer "B.Cu")
		(at 176.97704 -32.951928 -90)
		(property "Reference" "PR4540"
			(at 0 0 90)
			(layer "B.SilkS")
			(hide yes)
			(effects
				(font
					(size 1.27 1.27)
				)
				(justify mirror)
			)
		)
		(property "Value" ""
			(at 0 0 90)
			(layer "B.Fab")
			(effects
				(font
					(size 1.27 1.27)
				)
				(justify mirror)
			)
		)
		(duplicate_pad_numbers_are_jumpers no)
		(fp_line
			(start -0.7874 0.4064)
			(end 0.7874 0.4064)
			(stroke
				(width 0.1524)
				(type default)
			)
			(layer "B.SilkS")
		)
		(fp_line
			(start 0.7874 0.4064)
			(end 0.7874 -0.4064)
			(stroke
				(width 0.1524)
				(type default)
			)
			(layer "B.SilkS")
		)
		(fp_line
			(start -0.7874 -0.4064)
			(end -0.7874 0.4064)
			(stroke
				(width 0.1524)
				(type default)
			)
			(layer "B.SilkS")
		)
		(fp_line
			(start 0.7874 -0.4064)
			(end -0.7874 -0.4064)
			(stroke
				(width 0.1524)
				(type default)
			)
			(layer "B.SilkS")
		)
		(fp_line
			(start -0.67945 0.3048)
			(end -0.120396 0.3048)
			(stroke
				(width 0.1)
				(type default)
			)
			(layer "B.Fab")
		)
		(fp_line
			(start -0.120396 0.3048)
			(end -0.120396 0.2794)
			(stroke
				(width 0.1)
				(type default)
			)
			(layer "B.Fab")
		)
		(fp_line
			(start 0.12065 0.3048)
			(end 0.67945 0.3048)
			(stroke
				(width 0.1)
				(type default)
			)
			(layer "B.Fab")
		)
		(fp_line
			(start 0.67945 0.3048)
			(end 0.67945 -0.305054)
			(stroke
				(width 0.1)
				(type default)
			)
			(layer "B.Fab")
		)
		(fp_line
			(start -0.120396 0.2794)
			(end 0.12065 0.2794)
			(stroke
				(width 0.1)
				(type default)
			)
			(layer "B.Fab")
		)
		(fp_line
			(start 0.12065 0.2794)
			(end 0.12065 0.3048)
			(stroke
				(width 0.1)
				(type default)
			)
			(layer "B.Fab")
		)
		(fp_line
			(start -0.12065 -0.2794)
			(end -0.12065 -0.3048)
			(stroke
				(width 0.1)
				(type default)
			)
			(layer "B.Fab")
		)
		(fp_line
			(start 0.12065 -0.2794)
			(end -0.12065 -0.2794)
			(stroke
				(width 0.1)
				(type default)
			)
			(layer "B.Fab")
		)
		(fp_line
			(start -0.67945 -0.3048)
			(end -0.67945 0.3048)
			(stroke
				(width 0.1)
				(type default)
			)
			(layer "B.Fab")
		)
		(fp_line
			(start -0.12065 -0.3048)
			(end -0.67945 -0.3048)
			(stroke
				(width 0.1)
				(type default)
			)
			(layer "B.Fab")
		)
		(fp_line
			(start 0.12065 -0.305054)
			(end 0.12065 -0.2794)
			(stroke
				(width 0.1)
				(type default)
			)
			(layer "B.Fab")
		)
		(fp_line
			(start 0.67945 -0.305054)
			(end 0.12065 -0.305054)
			(stroke
				(width 0.1)
				(type default)
			)
			(layer "B.Fab")
		)
		(pad "1" smd circle
			(at 0.40005 0 90)
			(size 0 0)
			(layers "B.Cu" "B.Mask" "B.Paste")
			(net "P12V_SCM_ISET")
		)
		(pad "2" smd circle
			(at -0.40005 0 90)
			(size 0 0)
			(layers "B.Cu" "B.Mask" "B.Paste")
			(net "P12V_SCM_ISET_R")
		)
	)
)
